FILE_TYPE = CONNECTIVITY;
{Allegro Design Entry HDL 16.6-p007 (v16-6-112F) 10/10/2012}
"PAGE_NUMBER" = 1;
0"NC";
END.
